(kicad_pcb
	(version 20260206)
	(generator "pcbnew")
	(generator_version "10.0")
	(general
		(thickness 1.6)
		(legacy_teardrops no)
	)
	(paper "A4")
	(title_block
		(title "04192023_DAF0TMB3IC0_F0TG_MB_C_brd_V02_OCP.brd")
		(comment 1 "Grand Teton / footprints 5539-5546 of 8354")
	)
	(layers
		(0 "F.Cu" signal "TOP")
		(4 "In1.Cu" signal "GND")
		(6 "In2.Cu" signal "IN1")
		(8 "In3.Cu" signal "GND1")
		(10 "In4.Cu" signal "IN2")
		(12 "In5.Cu" signal "GND2")
		(14 "In6.Cu" signal "IN3")
		(16 "In7.Cu" signal "GND3")
		(18 "In8.Cu" signal "VCC")
		(20 "In9.Cu" signal "VCC1")
		(22 "In10.Cu" signal "GND4")
		(24 "In11.Cu" signal "IN4")
		(26 "In12.Cu" signal "GND5")
		(28 "In13.Cu" signal "IN5")
		(30 "In14.Cu" signal "GND6")
		(32 "In15.Cu" signal "IN6")
		(34 "In16.Cu" signal "GND7")
		(2 "B.Cu" signal "BOTTOM")
		(9 "F.Adhes" user "F.Adhesive")
		(11 "B.Adhes" user "B.Adhesive")
		(13 "F.Paste" user "Package Geometry/Pastemask Top")
		(15 "B.Paste" user "Package Geometry/Pastemask Bottom")
		(5 "F.SilkS" user "Ref Des/Silkscreen Top")
		(7 "B.SilkS" user "Ref Des/Silkscreen Bottom")
		(1 "F.Mask" user "Board Geometry/Soldermask Top")
		(3 "B.Mask" user "Board Geometry/Soldermask Bottom")
		(17 "Dwgs.User" user "User.Drawings")
		(19 "Cmts.User" user "User.Comments")
		(21 "Eco1.User" user "User.Eco1")
		(23 "Eco2.User" user "User.Eco2")
		(25 "Edge.Cuts" user "Board Geometry/Outline")
		(27 "Margin" user)
		(31 "F.CrtYd" user "Package Geometry/Place Bound Top")
		(29 "B.CrtYd" user "Package Geometry/Place Bound Bottom")
		(35 "F.Fab" user "Ref Des/Assembly Top")
		(33 "B.Fab" user "Ref Des/Assembly Bottom")
	)
	(footprint ""
		(layer "B.Cu")
		(at 254.635 -331.978 180)
		(property "Reference" "R851"
			(at 0 0 0)
			(layer "B.SilkS")
			(hide yes)
			(effects
				(font
					(size 1.27 1.27)
				)
				(justify mirror)
			)
		)
		(property "Value" ""
			(at 0 0 0)
			(layer "B.Fab")
			(effects
				(font
					(size 1.27 1.27)
				)
				(justify mirror)
			)
		)
		(duplicate_pad_numbers_are_jumpers no)
		(fp_line
			(start 0.32512 0.175006)
			(end 0.32512 -0.175006)
			(stroke
				(width 0.1)
				(type default)
			)
			(layer "B.Fab")
		)
		(fp_line
			(start 0.32512 -0.175006)
			(end -0.32512 -0.175006)
			(stroke
				(width 0.1)
				(type default)
			)
			(layer "B.Fab")
		)
		(fp_line
			(start -0.32512 0.175006)
			(end 0.32512 0.175006)
			(stroke
				(width 0.1)
				(type default)
			)
			(layer "B.Fab")
		)
		(fp_line
			(start -0.32512 -0.175006)
			(end -0.32512 0.175006)
			(stroke
				(width 0.1)
				(type default)
			)
			(layer "B.Fab")
		)
		(pad "1" smd rect
			(at 0.2667 0)
			(size 0.3048 0.381)
			(layers "B.Cu" "B.Mask" "B.Paste")
			(net "SMB_MUX_RT_ROM_SCL")
		)
		(pad "2" smd rect
			(at -0.2667 0 180)
			(size 0.3048 0.381)
			(layers "B.Cu" "B.Mask" "B.Paste")
			(net "SMB_MUX_RT_ROM_R1_SCL")
		)
	)
	(footprint ""
		(layer "B.Cu")
		(at 283.980636 -195.859146 180)
		(property "Reference" "R1676"
			(at 0 0 0)
			(layer "B.SilkS")
			(hide yes)
			(effects
				(font
					(size 1.27 1.27)
				)
				(justify mirror)
			)
		)
		(property "Value" ""
			(at 0 0 0)
			(layer "B.Fab")
			(effects
				(font
					(size 1.27 1.27)
				)
				(justify mirror)
			)
		)
		(duplicate_pad_numbers_are_jumpers no)
		(fp_line
			(start 0.7874 0.4064)
			(end 0.7874 -0.4064)
			(stroke
				(width 0.1524)
				(type default)
			)
			(layer "B.SilkS")
		)
		(fp_line
			(start 0.7874 -0.4064)
			(end -0.7874 -0.4064)
			(stroke
				(width 0.1524)
				(type default)
			)
			(layer "B.SilkS")
		)
		(fp_line
			(start -0.7874 0.4064)
			(end 0.7874 0.4064)
			(stroke
				(width 0.1524)
				(type default)
			)
			(layer "B.SilkS")
		)
		(fp_line
			(start -0.7874 -0.4064)
			(end -0.7874 0.4064)
			(stroke
				(width 0.1524)
				(type default)
			)
			(layer "B.SilkS")
		)
		(fp_line
			(start 0.67945 0.3048)
			(end 0.67945 -0.305054)
			(stroke
				(width 0.1)
				(type default)
			)
			(layer "B.Fab")
		)
		(fp_line
			(start 0.67945 -0.305054)
			(end 0.12065 -0.305054)
			(stroke
				(width 0.1)
				(type default)
			)
			(layer "B.Fab")
		)
		(fp_line
			(start 0.12065 0.3048)
			(end 0.67945 0.3048)
			(stroke
				(width 0.1)
				(type default)
			)
			(layer "B.Fab")
		)
		(fp_line
			(start 0.12065 0.2794)
			(end 0.12065 0.3048)
			(stroke
				(width 0.1)
				(type default)
			)
			(layer "B.Fab")
		)
		(fp_line
			(start 0.12065 -0.2794)
			(end -0.12065 -0.2794)
			(stroke
				(width 0.1)
				(type default)
			)
			(layer "B.Fab")
		)
		(fp_line
			(start 0.12065 -0.305054)
			(end 0.12065 -0.2794)
			(stroke
				(width 0.1)
				(type default)
			)
			(layer "B.Fab")
		)
		(fp_line
			(start -0.120396 0.3048)
			(end -0.120396 0.2794)
			(stroke
				(width 0.1)
				(type default)
			)
			(layer "B.Fab")
		)
		(fp_line
			(start -0.120396 0.2794)
			(end 0.12065 0.2794)
			(stroke
				(width 0.1)
				(type default)
			)
			(layer "B.Fab")
		)
		(fp_line
			(start -0.12065 -0.2794)
			(end -0.12065 -0.3048)
			(stroke
				(width 0.1)
				(type default)
			)
			(layer "B.Fab")
		)
		(fp_line
			(start -0.12065 -0.3048)
			(end -0.67945 -0.3048)
			(stroke
				(width 0.1)
				(type default)
			)
			(layer "B.Fab")
		)
		(fp_line
			(start -0.67945 0.3048)
			(end -0.120396 0.3048)
			(stroke
				(width 0.1)
				(type default)
			)
			(layer "B.Fab")
		)
		(fp_line
			(start -0.67945 -0.3048)
			(end -0.67945 0.3048)
			(stroke
				(width 0.1)
				(type default)
			)
			(layer "B.Fab")
		)
		(pad "1" smd circle
			(at 0.40005 0)
			(size 0 0)
			(layers "B.Cu" "B.Mask" "B.Paste")
			(net "I3C_SPD_DDRAF_CPU0_SDA")
		)
		(pad "2" smd circle
			(at -0.40005 0)
			(size 0 0)
			(layers "B.Cu" "B.Mask" "B.Paste")
			(net "I3C_SPD_DDRD_CPU0_SDA")
		)
	)
	(footprint ""
		(layer "B.Cu")
		(at 152.992836 -16.851122 -90)
		(property "Reference" "R3227"
			(at 0 0 90)
			(layer "B.SilkS")
			(hide yes)
			(effects
				(font
					(size 1.27 1.27)
				)
				(justify mirror)
			)
		)
		(property "Value" ""
			(at 0 0 90)
			(layer "B.Fab")
			(effects
				(font
					(size 1.27 1.27)
				)
				(justify mirror)
			)
		)
		(duplicate_pad_numbers_are_jumpers no)
		(fp_line
			(start -0.7874 0.4064)
			(end 0.7874 0.4064)
			(stroke
				(width 0.1524)
				(type default)
			)
			(layer "B.SilkS")
		)
		(fp_line
			(start 0.7874 0.4064)
			(end 0.7874 -0.4064)
			(stroke
				(width 0.1524)
				(type default)
			)
			(layer "B.SilkS")
		)
		(fp_line
			(start -0.7874 -0.4064)
			(end -0.7874 0.4064)
			(stroke
				(width 0.1524)
				(type default)
			)
			(layer "B.SilkS")
		)
		(fp_line
			(start 0.7874 -0.4064)
			(end -0.7874 -0.4064)
			(stroke
				(width 0.1524)
				(type default)
			)
			(layer "B.SilkS")
		)
		(fp_line
			(start -0.67945 0.3048)
			(end -0.120396 0.3048)
			(stroke
				(width 0.1)
				(type default)
			)
			(layer "B.Fab")
		)
		(fp_line
			(start -0.120396 0.3048)
			(end -0.120396 0.2794)
			(stroke
				(width 0.1)
				(type default)
			)
			(layer "B.Fab")
		)
		(fp_line
			(start 0.12065 0.3048)
			(end 0.67945 0.3048)
			(stroke
				(width 0.1)
				(type default)
			)
			(layer "B.Fab")
		)
		(fp_line
			(start 0.67945 0.3048)
			(end 0.67945 -0.305054)
			(stroke
				(width 0.1)
				(type default)
			)
			(layer "B.Fab")
		)
		(fp_line
			(start -0.120396 0.2794)
			(end 0.12065 0.2794)
			(stroke
				(width 0.1)
				(type default)
			)
			(layer "B.Fab")
		)
		(fp_line
			(start 0.12065 0.2794)
			(end 0.12065 0.3048)
			(stroke
				(width 0.1)
				(type default)
			)
			(layer "B.Fab")
		)
		(fp_line
			(start -0.12065 -0.2794)
			(end -0.12065 -0.3048)
			(stroke
				(width 0.1)
				(type default)
			)
			(layer "B.Fab")
		)
		(fp_line
			(start 0.12065 -0.2794)
			(end -0.12065 -0.2794)
			(stroke
				(width 0.1)
				(type default)
			)
			(layer "B.Fab")
		)
		(fp_line
			(start -0.67945 -0.3048)
			(end -0.67945 0.3048)
			(stroke
				(width 0.1)
				(type default)
			)
			(layer "B.Fab")
		)
		(fp_line
			(start -0.12065 -0.3048)
			(end -0.67945 -0.3048)
			(stroke
				(width 0.1)
				(type default)
			)
			(layer "B.Fab")
		)
		(fp_line
			(start 0.12065 -0.305054)
			(end 0.12065 -0.2794)
			(stroke
				(width 0.1)
				(type default)
			)
			(layer "B.Fab")
		)
		(fp_line
			(start 0.67945 -0.305054)
			(end 0.12065 -0.305054)
			(stroke
				(width 0.1)
				(type default)
			)
			(layer "B.Fab")
		)
		(pad "1" smd circle
			(at 0.40005 0 90)
			(size 0 0)
			(layers "B.Cu" "B.Mask" "B.Paste")
			(net "SMB_1_BMC_GPU_SDA")
		)
		(pad "2" smd circle
			(at -0.40005 0 90)
			(size 0 0)
			(layers "B.Cu" "B.Mask" "B.Paste")
			(net "P3V3_AUX")
		)
	)
	(footprint ""
		(layer "B.Cu")
		(at 354.915724 -340.002368 90)
		(property "Reference" "PC118_6"
			(at 0 0 90)
			(layer "B.SilkS")
			(hide yes)
			(effects
				(font
					(size 1.27 1.27)
				)
				(justify mirror)
			)
		)
		(property "Value" ""
			(at 0 0 90)
			(layer "B.Fab")
			(effects
				(font
					(size 1.27 1.27)
				)
				(justify mirror)
			)
		)
		(duplicate_pad_numbers_are_jumpers no)
		(fp_line
			(start 1.524 -0.762)
			(end -1.524 -0.762)
			(stroke
				(width 0.1524)
				(type default)
			)
			(layer "B.SilkS")
		)
		(fp_line
			(start -1.524 -0.762)
			(end -1.524 0.762)
			(stroke
				(width 0.1524)
				(type default)
			)
			(layer "B.SilkS")
		)
		(fp_line
			(start 1.524 0.762)
			(end 1.524 -0.762)
			(stroke
				(width 0.1524)
				(type default)
			)
			(layer "B.SilkS")
		)
		(fp_line
			(start -1.524 0.762)
			(end 1.524 0.762)
			(stroke
				(width 0.1524)
				(type default)
			)
			(layer "B.SilkS")
		)
		(fp_line
			(start 1.1049 -0.724916)
			(end 1.1049 0.724916)
			(stroke
				(width 0.1)
				(type default)
			)
			(layer "B.Fab")
		)
		(fp_line
			(start -1.1049 -0.724916)
			(end 1.1049 -0.724916)
			(stroke
				(width 0.1)
				(type default)
			)
			(layer "B.Fab")
		)
		(fp_line
			(start 1.1049 0.724916)
			(end -1.1049 0.724916)
			(stroke
				(width 0.1)
				(type default)
			)
			(layer "B.Fab")
		)
		(fp_line
			(start -1.1049 0.724916)
			(end -1.1049 -0.724916)
			(stroke
				(width 0.1)
				(type default)
			)
			(layer "B.Fab")
		)
		(pad "1" smd rect
			(at 0.889 0 90)
			(size 1.016 1.27)
			(layers "B.Cu" "B.Mask" "B.Paste")
			(net "SW_P12V_AUX_PVDDCR_CPU1_P0_FLT")
		)
		(pad "2" smd rect
			(at -0.889 0 90)
			(size 1.016 1.27)
			(layers "B.Cu" "B.Mask" "B.Paste")
			(net "GND")
		)
	)
	(footprint ""
		(layer "B.Cu")
		(at 305.423316 -426.466 180)
		(property "Reference" "R1445"
			(at 0 0 0)
			(layer "B.SilkS")
			(hide yes)
			(effects
				(font
					(size 1.27 1.27)
				)
				(justify mirror)
			)
		)
		(property "Value" ""
			(at 0 0 0)
			(layer "B.Fab")
			(effects
				(font
					(size 1.27 1.27)
				)
				(justify mirror)
			)
		)
		(duplicate_pad_numbers_are_jumpers no)
		(fp_line
			(start 0.32512 0.175006)
			(end 0.32512 -0.175006)
			(stroke
				(width 0.1)
				(type default)
			)
			(layer "B.Fab")
		)
		(fp_line
			(start 0.32512 -0.175006)
			(end -0.32512 -0.175006)
			(stroke
				(width 0.1)
				(type default)
			)
			(layer "B.Fab")
		)
		(fp_line
			(start -0.32512 0.175006)
			(end 0.32512 0.175006)
			(stroke
				(width 0.1)
				(type default)
			)
			(layer "B.Fab")
		)
		(fp_line
			(start -0.32512 -0.175006)
			(end -0.32512 0.175006)
			(stroke
				(width 0.1)
				(type default)
			)
			(layer "B.Fab")
		)
		(pad "1" smd rect
			(at 0.2667 0)
			(size 0.3048 0.381)
			(layers "B.Cu" "B.Mask" "B.Paste")
			(net "P1V8_CPU0_RT_1D")
		)
		(pad "2" smd rect
			(at -0.2667 0 180)
			(size 0.3048 0.381)
			(layers "B.Cu" "B.Mask" "B.Paste")
			(net "JTAG_TDO_RT_CPU0_P0")
		)
	)
	(footprint ""
		(layer "B.Cu")
		(at 171.196 -118.328948)
		(property "Reference" "R891"
			(at 0 0 0)
			(layer "B.SilkS")
			(hide yes)
			(effects
				(font
					(size 1.27 1.27)
				)
				(justify mirror)
			)
		)
		(property "Value" ""
			(at 0 0 0)
			(layer "B.Fab")
			(effects
				(font
					(size 1.27 1.27)
				)
				(justify mirror)
			)
		)
		(duplicate_pad_numbers_are_jumpers no)
		(fp_line
			(start -0.7874 -0.4064)
			(end -0.7874 0.4064)
			(stroke
				(width 0.1524)
				(type default)
			)
			(layer "B.SilkS")
		)
		(fp_line
			(start -0.7874 0.4064)
			(end 0.7874 0.4064)
			(stroke
				(width 0.1524)
				(type default)
			)
			(layer "B.SilkS")
		)
		(fp_line
			(start 0.7874 -0.4064)
			(end -0.7874 -0.4064)
			(stroke
				(width 0.1524)
				(type default)
			)
			(layer "B.SilkS")
		)
		(fp_line
			(start 0.7874 0.4064)
			(end 0.7874 -0.4064)
			(stroke
				(width 0.1524)
				(type default)
			)
			(layer "B.SilkS")
		)
		(fp_line
			(start -0.67945 -0.3048)
			(end -0.67945 0.3048)
			(stroke
				(width 0.1)
				(type default)
			)
			(layer "B.Fab")
		)
		(fp_line
			(start -0.67945 0.3048)
			(end -0.120396 0.3048)
			(stroke
				(width 0.1)
				(type default)
			)
			(layer "B.Fab")
		)
		(fp_line
			(start -0.12065 -0.3048)
			(end -0.67945 -0.3048)
			(stroke
				(width 0.1)
				(type default)
			)
			(layer "B.Fab")
		)
		(fp_line
			(start -0.12065 -0.2794)
			(end -0.12065 -0.3048)
			(stroke
				(width 0.1)
				(type default)
			)
			(layer "B.Fab")
		)
		(fp_line
			(start -0.120396 0.2794)
			(end 0.12065 0.2794)
			(stroke
				(width 0.1)
				(type default)
			)
			(layer "B.Fab")
		)
		(fp_line
			(start -0.120396 0.3048)
			(end -0.120396 0.2794)
			(stroke
				(width 0.1)
				(type default)
			)
			(layer "B.Fab")
		)
		(fp_line
			(start 0.12065 -0.305054)
			(end 0.12065 -0.2794)
			(stroke
				(width 0.1)
				(type default)
			)
			(layer "B.Fab")
		)
		(fp_line
			(start 0.12065 -0.2794)
			(end -0.12065 -0.2794)
			(stroke
				(width 0.1)
				(type default)
			)
			(layer "B.Fab")
		)
		(fp_line
			(start 0.12065 0.2794)
			(end 0.12065 0.3048)
			(stroke
				(width 0.1)
				(type default)
			)
			(layer "B.Fab")
		)
		(fp_line
			(start 0.12065 0.3048)
			(end 0.67945 0.3048)
			(stroke
				(width 0.1)
				(type default)
			)
			(layer "B.Fab")
		)
		(fp_line
			(start 0.67945 -0.305054)
			(end 0.12065 -0.305054)
			(stroke
				(width 0.1)
				(type default)
			)
			(layer "B.Fab")
		)
		(fp_line
			(start 0.67945 0.3048)
			(end 0.67945 -0.305054)
			(stroke
				(width 0.1)
				(type default)
			)
			(layer "B.Fab")
		)
		(pad "1" smd circle
			(at 0.40005 0 180)
			(size 0 0)
			(layers "B.Cu" "B.Mask" "B.Paste")
			(net "SCM_SPARE_1")
		)
		(pad "2" smd circle
			(at -0.40005 0 180)
			(size 0 0)
			(layers "B.Cu" "B.Mask" "B.Paste")
			(net "GND")
		)
	)
	(footprint ""
		(layer "B.Cu")
		(at 194.67957 -342.10244 -90)
		(property "Reference" "PC523_2"
			(at 0 0 90)
			(layer "B.SilkS")
			(hide yes)
			(effects
				(font
					(size 1.27 1.27)
				)
				(justify mirror)
			)
		)
		(property "Value" ""
			(at 0 0 90)
			(layer "B.Fab")
			(effects
				(font
					(size 1.27 1.27)
				)
				(justify mirror)
			)
		)
		(duplicate_pad_numbers_are_jumpers no)
		(fp_line
			(start -1.524 0.762)
			(end 1.524 0.762)
			(stroke
				(width 0.1524)
				(type default)
			)
			(layer "B.SilkS")
		)
		(fp_line
			(start 1.524 0.762)
			(end 1.524 -0.762)
			(stroke
				(width 0.1524)
				(type default)
			)
			(layer "B.SilkS")
		)
		(fp_line
			(start -1.524 -0.762)
			(end -1.524 0.762)
			(stroke
				(width 0.1524)
				(type default)
			)
			(layer "B.SilkS")
		)
		(fp_line
			(start 1.524 -0.762)
			(end -1.524 -0.762)
			(stroke
				(width 0.1524)
				(type default)
			)
			(layer "B.SilkS")
		)
		(fp_line
			(start -1.1049 0.724916)
			(end -1.1049 -0.724916)
			(stroke
				(width 0.1)
				(type default)
			)
			(layer "B.Fab")
		)
		(fp_line
			(start 1.1049 0.724916)
			(end -1.1049 0.724916)
			(stroke
				(width 0.1)
				(type default)
			)
			(layer "B.Fab")
		)
		(fp_line
			(start -1.1049 -0.724916)
			(end 1.1049 -0.724916)
			(stroke
				(width 0.1)
				(type default)
			)
			(layer "B.Fab")
		)
		(fp_line
			(start 1.1049 -0.724916)
			(end 1.1049 0.724916)
			(stroke
				(width 0.1)
				(type default)
			)
			(layer "B.Fab")
		)
		(pad "1" smd rect
			(at 0.889 0 270)
			(size 1.016 1.27)
			(layers "B.Cu" "B.Mask" "B.Paste")
			(net "PVDD11_S3_P1")
		)
		(pad "2" smd rect
			(at -0.889 0 270)
			(size 1.016 1.27)
			(layers "B.Cu" "B.Mask" "B.Paste")
			(net "GND")
		)
	)
	(footprint ""
		(layer "B.Cu")
		(at 105.695242 -412.03372 90)
		(property "Reference" "R2656"
			(at 0 0 90)
			(layer "B.SilkS")
			(hide yes)
			(effects
				(font
					(size 1.27 1.27)
				)
				(justify mirror)
			)
		)
		(property "Value" ""
			(at 0 0 90)
			(layer "B.Fab")
			(effects
				(font
					(size 1.27 1.27)
				)
				(justify mirror)
			)
		)
		(duplicate_pad_numbers_are_jumpers no)
		(fp_line
			(start 0.7874 -0.4064)
			(end -0.7874 -0.4064)
			(stroke
				(width 0.1524)
				(type default)
			)
			(layer "B.SilkS")
		)
		(fp_line
			(start -0.7874 -0.4064)
			(end -0.7874 0.4064)
			(stroke
				(width 0.1524)
				(type default)
			)
			(layer "B.SilkS")
		)
		(fp_line
			(start 0.7874 0.4064)
			(end 0.7874 -0.4064)
			(stroke
				(width 0.1524)
				(type default)
			)
			(layer "B.SilkS")
		)
		(fp_line
			(start -0.7874 0.4064)
			(end 0.7874 0.4064)
			(stroke
				(width 0.1524)
				(type default)
			)
			(layer "B.SilkS")
		)
		(fp_line
			(start 0.67945 -0.305054)
			(end 0.12065 -0.305054)
			(stroke
				(width 0.1)
				(type default)
			)
			(layer "B.Fab")
		)
		(fp_line
			(start 0.12065 -0.305054)
			(end 0.12065 -0.2794)
			(stroke
				(width 0.1)
				(type default)
			)
			(layer "B.Fab")
		)
		(fp_line
			(start -0.12065 -0.3048)
			(end -0.67945 -0.3048)
			(stroke
				(width 0.1)
				(type default)
			)
			(layer "B.Fab")
		)
		(fp_line
			(start -0.67945 -0.3048)
			(end -0.67945 0.3048)
			(stroke
				(width 0.1)
				(type default)
			)
			(layer "B.Fab")
		)
		(fp_line
			(start 0.12065 -0.2794)
			(end -0.12065 -0.2794)
			(stroke
				(width 0.1)
				(type default)
			)
			(layer "B.Fab")
		)
		(fp_line
			(start -0.12065 -0.2794)
			(end -0.12065 -0.3048)
			(stroke
				(width 0.1)
				(type default)
			)
			(layer "B.Fab")
		)
		(fp_line
			(start 0.12065 0.2794)
			(end 0.12065 0.3048)
			(stroke
				(width 0.1)
				(type default)
			)
			(layer "B.Fab")
		)
		(fp_line
			(start -0.120396 0.2794)
			(end 0.12065 0.2794)
			(stroke
				(width 0.1)
				(type default)
			)
			(layer "B.Fab")
		)
		(fp_line
			(start 0.67945 0.3048)
			(end 0.67945 -0.305054)
			(stroke
				(width 0.1)
				(type default)
			)
			(layer "B.Fab")
		)
		(fp_line
			(start 0.12065 0.3048)
			(end 0.67945 0.3048)
			(stroke
				(width 0.1)
				(type default)
			)
			(layer "B.Fab")
		)
		(fp_line
			(start -0.120396 0.3048)
			(end -0.120396 0.2794)
			(stroke
				(width 0.1)
				(type default)
			)
			(layer "B.Fab")
		)
		(fp_line
			(start -0.67945 0.3048)
			(end -0.120396 0.3048)
			(stroke
				(width 0.1)
				(type default)
			)
			(layer "B.Fab")
		)
		(pad "1" smd circle
			(at 0.40005 0 270)
			(size 0 0)
			(layers "B.Cu" "B.Mask" "B.Paste")
			(net "HGX_DETECT_N_ISO")
		)
		(pad "2" smd circle
			(at -0.40005 0 270)
			(size 0 0)
			(layers "B.Cu" "B.Mask" "B.Paste")
			(net "GND")
		)
	)
)
